# discovery-power-board-v1-revB — CONN_02x04_4.2mm.kicad_mod (kicad-footprint)
(module CONN_02x04_4.2mm (layer F.Cu) 
  (fp_text reference REF** (at 1.8415 -10.24128) (layer F.SilkS)
    (effects (font (size 1 1) (thickness 0.15)))
  )
  (fp_text value CONN_02x04_4.2mm (at 10.69848 0.8509) (layer F.Fab)
    (effects (font (size 1 1) (thickness 0.15)))
  )
  (fp_line (start 0 0) (end 0 -9.6) (layer F.SilkS) (width 0.1))
  (fp_line (start 0 0) (end 18 0) (layer F.SilkS) (width 0.1))
  (fp_line (start 18 0) (end 18 -9.6) (layer F.SilkS) (width 0.1))
  (fp_line (start 0 -9.6) (end 18 -9.6) (layer F.SilkS) (width 0.1))
  (fp_line (start -4 -11.05) (end -4 0.1) (layer F.CrtYd) (width 0.1))
  (fp_line (start -4 0.1) (end 22 0.1) (layer F.CrtYd) (width 0.1))
  (fp_line (start 22 0.1) (end 22 -11.05) (layer F.CrtYd) (width 0.1))
  (fp_line (start 22 -11.05) (end -4 -11.05) (layer F.CrtYd) (width 0.1))
  (fp_line (start 8.2 -11) (end 8.2 -9.6) (layer F.SilkS) (width 0.1))
  (fp_line (start 8.2 -11) (end 10.2 -11) (layer F.SilkS) (width 0.1))
  (fp_line (start 10.2 -11) (end 10.2 -9.6) (layer F.SilkS) (width 0.1))
  (pad "" np_thru_hole circle (at -2 -7.1) (size 4 4) (drill 3.03) (layers *.Cu *.Mask))
  (pad "" np_thru_hole circle (at 20 -7.1) (size 4 4) (drill 3.03) (layers *.Cu *.Mask))
  (pad 1 thru_hole circle (at 15.3 -2.7) (size 2.5 2.5) (drill 1.8) (layers *.Cu *.Mask))
  (pad 2 thru_hole circle (at 11.1 -2.7) (size 2.5 2.5) (drill 1.8) (layers *.Cu *.Mask))
  (pad 3 thru_hole circle (at 6.9 -2.7) (size 2.5 2.5) (drill 1.8) (layers *.Cu *.Mask))
  (pad 4 thru_hole circle (at 2.7 -2.7) (size 2.5 2.5) (drill 1.8) (layers *.Cu *.Mask))
  (pad 5 thru_hole circle (at 15.3 -6.9) (size 2.5 2.5) (drill 1.8) (layers *.Cu *.Mask))
  (pad 6 thru_hole circle (at 11.1 -6.9) (size 2.5 2.5) (drill 1.8) (layers *.Cu *.Mask))
  (pad 7 thru_hole circle (at 6.9 -6.9) (size 2.5 2.5) (drill 1.8) (layers *.Cu *.Mask))
  (pad 8 thru_hole circle (at 2.7 -6.9) (size 2.5 2.5) (drill 1.8) (layers *.Cu *.Mask))
)
